(kicad_pcb
	(version 20260206)
	(generator "pcbnew")
	(generator_version "10.0")
	(general
		(thickness 1.6)
		(legacy_teardrops no)
	)
	(paper "A4")
	(title_block
		(title "baseboard — 13948-1b.1110WZS1818.brd")
		(comment 1 "Honey Badger (Wiwynn) / footprints 993-999 of 2523")
	)
	(layers
		(0 "F.Cu" signal "TOP")
		(4 "In1.Cu" signal "L2GND")
		(6 "In2.Cu" signal "L3")
		(8 "In3.Cu" signal "L4VCC")
		(10 "In4.Cu" signal "L5VCC")
		(12 "In5.Cu" signal "L6")
		(14 "In6.Cu" signal "L7GND")
		(2 "B.Cu" signal "BOTTOM")
		(9 "F.Adhes" user "F.Adhesive")
		(11 "B.Adhes" user "B.Adhesive")
		(13 "F.Paste" user "Package Geometry/Pastemask Top")
		(15 "B.Paste" user "Package Geometry/Pastemask Bottom")
		(5 "F.SilkS" user "Ref Des/Silkscreen Top")
		(7 "B.SilkS" user "Ref Des/Silkscreen Bottom")
		(1 "F.Mask" user "Board Geometry/Soldermask Top")
		(3 "B.Mask" user "Board Geometry/Soldermask Bottom")
		(17 "Dwgs.User" user "User.Drawings")
		(19 "Cmts.User" user "User.Comments")
		(21 "Eco1.User" user "User.Eco1")
		(23 "Eco2.User" user "User.Eco2")
		(25 "Edge.Cuts" user "Board Geometry/Outline")
		(27 "Margin" user)
		(31 "F.CrtYd" user "Package Geometry/Place Bound Top")
		(29 "B.CrtYd" user "Package Geometry/Place Bound Bottom")
		(35 "F.Fab" user "Ref Des/Assembly Top")
		(33 "B.Fab" user "Ref Des/Assembly Bottom")
	)
	(footprint ""
		(layer "F.Cu")
		(at 332.36154 -13.903198 -90)
		(property "Reference" "Q21"
			(at 0 0 270)
			(layer "F.SilkS")
			(hide yes)
			(effects
				(font
					(size 1.27 1.27)
				)
			)
		)
		(property "Value" "2N7002A-7-GP"
			(at 0.127 -8.9662 270)
			(unlocked yes)
			(layer "F.Fab")
			(hide yes)
			(effects
				(font
					(size 1.016 1.016)
					(thickness 0.1524)
				)
			)
		)
		(property "Device Type" "SOT23DGS2D4H48"
			(at 0.127 -10.4902 270)
			(unlocked yes)
			(layer "F.Fab")
			(hide yes)
			(effects
				(font
					(size 1.016 1.016)
					(thickness 0.1524)
				)
			)
		)
		(duplicate_pad_numbers_are_jumpers no)
		(fp_line
			(start -1.651 1.778)
			(end 1.651 1.778)
			(stroke
				(width 0.1524)
				(type default)
			)
			(layer "F.SilkS")
		)
		(fp_line
			(start 1.651 1.778)
			(end 1.651 -1.778)
			(stroke
				(width 0.1524)
				(type default)
			)
			(layer "F.SilkS")
		)
		(fp_line
			(start -1.651 -1.778)
			(end -1.651 1.778)
			(stroke
				(width 0.1524)
				(type default)
			)
			(layer "F.SilkS")
		)
		(fp_line
			(start 1.651 -1.778)
			(end -1.651 -1.778)
			(stroke
				(width 0.1524)
				(type default)
			)
			(layer "F.SilkS")
		)
		(fp_poly
			(pts
				(xy -1.778 1.8796) (xy -1.778 -1.8796) (xy 1.778 -1.8796) (xy 1.778 1.8796)
			)
			(stroke
				(width 0)
				(type default)
			)
			(fill no)
			(layer "F.CrtYd")
		)
		(fp_poly
			(pts
				(xy -1.778 1.8796) (xy -1.778 -1.8796) (xy 1.778 -1.8796) (xy 1.778 1.8796)
			)
			(stroke
				(width 0)
				(type default)
			)
			(fill no)
			(layer "F.Fab")
		)
		(pad "D" smd custom
			(at 0 -0.9525 270)
			(size 0.1905 0.1905)
			(layers "F.Cu" "F.Mask" "F.Paste")
			(net "EXP_BMC_HB_LED_D")
			(options
				(clearance outline)
				(anchor circle)
			)
			(primitives
				(gr_poly
					(pts
						(arc
							(start -0.1778 0.5715)
							(mid -0.321484 0.511984)
							(end -0.381 0.3683)
						)
						(arc
							(start -0.381 -0.3683)
							(mid -0.321484 -0.511984)
							(end -0.1778 -0.5715)
						)
						(arc
							(start 0.1778 -0.5715)
							(mid 0.321484 -0.511984)
							(end 0.381 -0.3683)
						)
						(arc
							(start 0.381 0.3683)
							(mid 0.321484 0.511984)
							(end 0.1778 0.5715)
						)
					)
					(width 0)
					(fill yes)
				)
			)
		)
		(pad "G" smd custom
			(at -0.98425 0.9525 270)
			(size 0.1905 0.1905)
			(layers "F.Cu" "F.Mask" "F.Paste")
			(net "HB_OUT")
			(options
				(clearance outline)
				(anchor circle)
			)
			(primitives
				(gr_poly
					(pts
						(arc
							(start -0.1778 0.5715)
							(mid -0.321484 0.511984)
							(end -0.381 0.3683)
						)
						(arc
							(start -0.381 -0.3683)
							(mid -0.321484 -0.511984)
							(end -0.1778 -0.5715)
						)
						(arc
							(start 0.1778 -0.5715)
							(mid 0.321484 -0.511984)
							(end 0.381 -0.3683)
						)
						(arc
							(start 0.381 0.3683)
							(mid 0.321484 0.511984)
							(end 0.1778 0.5715)
						)
					)
					(width 0)
					(fill yes)
				)
			)
		)
		(pad "S" smd custom
			(at 0.98425 0.9525 270)
			(size 0.1905 0.1905)
			(layers "F.Cu" "F.Mask" "F.Paste")
			(net "GND")
			(options
				(clearance outline)
				(anchor circle)
			)
			(primitives
				(gr_poly
					(pts
						(arc
							(start -0.1778 0.5715)
							(mid -0.321484 0.511984)
							(end -0.381 0.3683)
						)
						(arc
							(start -0.381 -0.3683)
							(mid -0.321484 -0.511984)
							(end -0.1778 -0.5715)
						)
						(arc
							(start 0.1778 -0.5715)
							(mid 0.321484 -0.511984)
							(end 0.381 -0.3683)
						)
						(arc
							(start 0.381 0.3683)
							(mid 0.321484 0.511984)
							(end 0.1778 0.5715)
						)
					)
					(width 0)
					(fill yes)
				)
			)
		)
	)
	(footprint ""
		(layer "F.Cu")
		(at 174.941992 -31.115 -90)
		(property "Reference" "C234"
			(at 0 0 270)
			(layer "F.SilkS")
			(hide yes)
			(effects
				(font
					(size 1.27 1.27)
				)
			)
		)
		(property "Value" "SC27P50V2JN-2DLGP"
			(at 1.1811 -2.7051 270)
			(unlocked yes)
			(layer "F.Fab")
			(hide yes)
			(effects
				(font
					(size 1.016 1.016)
					(thickness 0.1524)
				)
			)
		)
		(property "Device Type" "C402H22"
			(at 1.1811 -4.2291 270)
			(unlocked yes)
			(layer "F.Fab")
			(hide yes)
			(effects
				(font
					(size 1.016 1.016)
					(thickness 0.1524)
				)
			)
		)
		(duplicate_pad_numbers_are_jumpers no)
		(fp_rect
			(start -0.4318 0.9525)
			(end 0.4318 -0.9525)
			(stroke
				(width 0)
				(type default)
			)
			(fill no)
			(layer "F.CrtYd")
		)
		(fp_rect
			(start -0.4318 0.9525)
			(end 0.4318 -0.9525)
			(stroke
				(width 0)
				(type default)
			)
			(fill no)
			(layer "F.Fab")
		)
		(pad "1" smd custom
			(at 0 -0.4445 270)
			(size 0.1524 0.1524)
			(layers "F.Cu" "F.Mask" "F.Paste")
			(net "BCM5221_RX_C_DN")
			(options
				(clearance outline)
				(anchor circle)
			)
			(primitives
				(gr_poly
					(pts
						(arc
							(start 0.3048 -0.2032)
							(mid 0.275042 -0.275042)
							(end 0.2032 -0.3048)
						)
						(arc
							(start -0.2032 -0.3048)
							(mid -0.275042 -0.275042)
							(end -0.3048 -0.2032)
						)
						(arc
							(start -0.3048 0.2032)
							(mid -0.275042 0.275042)
							(end -0.2032 0.3048)
						)
						(arc
							(start 0.2032 0.3048)
							(mid 0.275042 0.275042)
							(end 0.3048 0.2032)
						)
					)
					(width 0)
					(fill yes)
				)
			)
		)
		(pad "2" smd custom
			(at 0 0.4445 270)
			(size 0.1524 0.1524)
			(layers "F.Cu" "F.Mask" "F.Paste")
			(net "BCM5221_RX_C_DP")
			(options
				(clearance outline)
				(anchor circle)
			)
			(primitives
				(gr_poly
					(pts
						(arc
							(start 0.3048 -0.2032)
							(mid 0.275042 -0.275042)
							(end 0.2032 -0.3048)
						)
						(arc
							(start -0.2032 -0.3048)
							(mid -0.275042 -0.275042)
							(end -0.3048 -0.2032)
						)
						(arc
							(start -0.3048 0.2032)
							(mid -0.275042 0.275042)
							(end -0.2032 0.3048)
						)
						(arc
							(start 0.2032 0.3048)
							(mid 0.275042 0.275042)
							(end 0.3048 0.2032)
						)
					)
					(width 0)
					(fill yes)
				)
			)
		)
	)
	(footprint ""
		(layer "F.Cu")
		(at 135.14197 -98.806 180)
		(property "Reference" "SC1268"
			(at 0 0 180)
			(layer "F.SilkS")
			(hide yes)
			(effects
				(font
					(size 1.27 1.27)
				)
			)
		)
		(property "Value" "SCD01U10V1KX-GP"
			(at -2.8321 -1.7399 180)
			(unlocked yes)
			(layer "F.Fab")
			(hide yes)
			(effects
				(font
					(size 1.016 1.016)
					(thickness 0.1524)
				)
			)
		)
		(property "Device Type" "C0201H13"
			(at -2.8321 -3.2639 180)
			(unlocked yes)
			(layer "F.Fab")
			(hide yes)
			(effects
				(font
					(size 1.016 1.016)
					(thickness 0.1524)
				)
			)
		)
		(duplicate_pad_numbers_are_jumpers no)
		(fp_rect
			(start -0.2794 0.6477)
			(end 0.2794 -0.6477)
			(stroke
				(width 0)
				(type default)
			)
			(fill no)
			(layer "F.CrtYd")
		)
		(fp_rect
			(start -0.2794 0.6477)
			(end 0.2794 -0.6477)
			(stroke
				(width 0)
				(type default)
			)
			(fill no)
			(layer "F.Fab")
		)
		(pad "1" smd custom
			(at 0 -0.2794 180)
			(size 0.0762 0.0762)
			(layers "F.Cu" "F.Mask" "F.Paste")
			(net "3X24_SAS_TX21_P")
			(options
				(clearance outline)
				(anchor circle)
			)
			(primitives
				(gr_poly
					(pts
						(arc
							(start 0.1524 -0.127)
							(mid 0.137521 -0.162921)
							(end 0.1016 -0.1778)
						)
						(arc
							(start -0.1016 -0.1778)
							(mid -0.137521 -0.162921)
							(end -0.1524 -0.127)
						)
						(arc
							(start -0.1524 0.127)
							(mid -0.137521 0.162921)
							(end -0.1016 0.1778)
						)
						(arc
							(start 0.1016 0.1778)
							(mid 0.137521 0.162921)
							(end 0.1524 0.127)
						)
					)
					(width 0)
					(fill yes)
				)
			)
		)
		(pad "2" smd custom
			(at 0 0.2794 180)
			(size 0.0762 0.0762)
			(layers "F.Cu" "F.Mask" "F.Paste")
			(net "SAS_EXP_GF_TX_DP1")
			(options
				(clearance outline)
				(anchor circle)
			)
			(primitives
				(gr_poly
					(pts
						(arc
							(start 0.1524 -0.127)
							(mid 0.137521 -0.162921)
							(end 0.1016 -0.1778)
						)
						(arc
							(start -0.1016 -0.1778)
							(mid -0.137521 -0.162921)
							(end -0.1524 -0.127)
						)
						(arc
							(start -0.1524 0.127)
							(mid -0.137521 0.162921)
							(end -0.1016 0.1778)
						)
						(arc
							(start 0.1016 0.1778)
							(mid 0.137521 0.162921)
							(end 0.1524 0.127)
						)
					)
					(width 0)
					(fill yes)
				)
			)
		)
	)
	(footprint ""
		(layer "F.Cu")
		(at 96.647 -4.191)
		(property "Reference" "SC1047"
			(at 0 0 0)
			(layer "F.SilkS")
			(hide yes)
			(effects
				(font
					(size 1.27 1.27)
				)
			)
		)
		(property "Value" "SCD1U16V2KX-3GP"
			(at 1.1811 -2.7051 0)
			(unlocked yes)
			(layer "F.Fab")
			(hide yes)
			(effects
				(font
					(size 1.016 1.016)
					(thickness 0.1524)
				)
			)
		)
		(property "Device Type" "C402H22"
			(at 1.1811 -4.2291 0)
			(unlocked yes)
			(layer "F.Fab")
			(hide yes)
			(effects
				(font
					(size 1.016 1.016)
					(thickness 0.1524)
				)
			)
		)
		(duplicate_pad_numbers_are_jumpers no)
		(fp_rect
			(start -0.4318 0.9525)
			(end 0.4318 -0.9525)
			(stroke
				(width 0)
				(type default)
			)
			(fill no)
			(layer "F.CrtYd")
		)
		(fp_rect
			(start -0.4318 0.9525)
			(end 0.4318 -0.9525)
			(stroke
				(width 0)
				(type default)
			)
			(fill no)
			(layer "F.Fab")
		)
		(pad "1" smd custom
			(at 0 -0.4445)
			(size 0.1524 0.1524)
			(layers "F.Cu" "F.Mask" "F.Paste")
			(net "P0V955_C")
			(options
				(clearance outline)
				(anchor circle)
			)
			(primitives
				(gr_poly
					(pts
						(arc
							(start 0.3048 -0.2032)
							(mid 0.275042 -0.275042)
							(end 0.2032 -0.3048)
						)
						(arc
							(start -0.2032 -0.3048)
							(mid -0.275042 -0.275042)
							(end -0.3048 -0.2032)
						)
						(arc
							(start -0.3048 0.2032)
							(mid -0.275042 0.275042)
							(end -0.2032 0.3048)
						)
						(arc
							(start 0.2032 0.3048)
							(mid 0.275042 0.275042)
							(end 0.3048 0.2032)
						)
					)
					(width 0)
					(fill yes)
				)
			)
		)
		(pad "2" smd custom
			(at 0 0.4445)
			(size 0.1524 0.1524)
			(layers "F.Cu" "F.Mask" "F.Paste")
			(net "GND")
			(options
				(clearance outline)
				(anchor circle)
			)
			(primitives
				(gr_poly
					(pts
						(arc
							(start 0.3048 -0.2032)
							(mid 0.275042 -0.275042)
							(end 0.2032 -0.3048)
						)
						(arc
							(start -0.2032 -0.3048)
							(mid -0.275042 -0.275042)
							(end -0.3048 -0.2032)
						)
						(arc
							(start -0.3048 0.2032)
							(mid -0.275042 0.275042)
							(end -0.2032 0.3048)
						)
						(arc
							(start 0.2032 0.3048)
							(mid 0.275042 0.275042)
							(end 0.3048 0.2032)
						)
					)
					(width 0)
					(fill yes)
				)
			)
		)
	)
	(footprint ""
		(layer "F.Cu")
		(at 105.93197 -114.3 180)
		(property "Reference" "SC1085"
			(at 0 0 180)
			(layer "F.SilkS")
			(hide yes)
			(effects
				(font
					(size 1.27 1.27)
				)
			)
		)
		(property "Value" "SCD01U10V1KX-GP"
			(at -2.8321 -1.7399 180)
			(unlocked yes)
			(layer "F.Fab")
			(hide yes)
			(effects
				(font
					(size 1.016 1.016)
					(thickness 0.1524)
				)
			)
		)
		(property "Device Type" "C0201H13"
			(at -2.8321 -3.2639 180)
			(unlocked yes)
			(layer "F.Fab")
			(hide yes)
			(effects
				(font
					(size 1.016 1.016)
					(thickness 0.1524)
				)
			)
		)
		(duplicate_pad_numbers_are_jumpers no)
		(fp_rect
			(start -0.2794 0.6477)
			(end 0.2794 -0.6477)
			(stroke
				(width 0)
				(type default)
			)
			(fill no)
			(layer "F.CrtYd")
		)
		(fp_rect
			(start -0.2794 0.6477)
			(end 0.2794 -0.6477)
			(stroke
				(width 0)
				(type default)
			)
			(fill no)
			(layer "F.Fab")
		)
		(pad "1" smd custom
			(at 0 -0.2794 180)
			(size 0.0762 0.0762)
			(layers "F.Cu" "F.Mask" "F.Paste")
			(net "SAS_HDD_TX9_P")
			(options
				(clearance outline)
				(anchor circle)
			)
			(primitives
				(gr_poly
					(pts
						(arc
							(start 0.1524 -0.127)
							(mid 0.137521 -0.162921)
							(end 0.1016 -0.1778)
						)
						(arc
							(start -0.1016 -0.1778)
							(mid -0.137521 -0.162921)
							(end -0.1524 -0.127)
						)
						(arc
							(start -0.1524 0.127)
							(mid -0.137521 0.162921)
							(end -0.1016 0.1778)
						)
						(arc
							(start 0.1016 0.1778)
							(mid 0.137521 0.162921)
							(end 0.1524 0.127)
						)
					)
					(width 0)
					(fill yes)
				)
			)
		)
		(pad "2" smd custom
			(at 0 0.2794 180)
			(size 0.0762 0.0762)
			(layers "F.Cu" "F.Mask" "F.Paste")
			(net "SAS_EXP_GF_TX_DP13")
			(options
				(clearance outline)
				(anchor circle)
			)
			(primitives
				(gr_poly
					(pts
						(arc
							(start 0.1524 -0.127)
							(mid 0.137521 -0.162921)
							(end 0.1016 -0.1778)
						)
						(arc
							(start -0.1016 -0.1778)
							(mid -0.137521 -0.162921)
							(end -0.1524 -0.127)
						)
						(arc
							(start -0.1524 0.127)
							(mid -0.137521 0.162921)
							(end -0.1016 0.1778)
						)
						(arc
							(start 0.1016 0.1778)
							(mid 0.137521 0.162921)
							(end 0.1524 0.127)
						)
					)
					(width 0)
					(fill yes)
				)
			)
		)
	)
	(footprint ""
		(layer "F.Cu")
		(at 94.107 -14.097 90)
		(property "Reference" "SC945"
			(at 0 0 90)
			(layer "F.SilkS")
			(hide yes)
			(effects
				(font
					(size 1.27 1.27)
				)
			)
		)
		(property "Value" "SC100U6D3V0MX-2GP"
			(at -0.00254 -4.78536 90)
			(unlocked yes)
			(layer "F.Fab")
			(hide yes)
			(effects
				(font
					(size 1.016 1.016)
					(thickness 0.1524)
				)
			)
		)
		(property "Device Type" "C1210H107"
			(at -0.00254 -6.38048 90)
			(unlocked yes)
			(layer "F.Fab")
			(hide yes)
			(effects
				(font
					(size 1.016 1.016)
					(thickness 0.1524)
				)
			)
		)
		(duplicate_pad_numbers_are_jumpers no)
		(fp_line
			(start 1.5748 -2.3368)
			(end -1.5748 -2.3368)
			(stroke
				(width 0.1524)
				(type default)
			)
			(layer "F.SilkS")
		)
		(fp_line
			(start -1.5748 -2.3368)
			(end -1.5748 -0.762)
			(stroke
				(width 0.1524)
				(type default)
			)
			(layer "F.SilkS")
		)
		(fp_line
			(start 1.5748 -0.762)
			(end 1.5748 -2.3368)
			(stroke
				(width 0.1524)
				(type default)
			)
			(layer "F.SilkS")
		)
		(fp_line
			(start -1.5748 0.762)
			(end -1.5748 2.3368)
			(stroke
				(width 0.1524)
				(type default)
			)
			(layer "F.SilkS")
		)
		(fp_line
			(start 1.5748 2.3368)
			(end 1.5748 0.762)
			(stroke
				(width 0.1524)
				(type default)
			)
			(layer "F.SilkS")
		)
		(fp_line
			(start -1.5748 2.3368)
			(end 1.5748 2.3368)
			(stroke
				(width 0.1524)
				(type default)
			)
			(layer "F.SilkS")
		)
		(fp_rect
			(start -1.651 2.413)
			(end 1.651 -2.413)
			(stroke
				(width 0)
				(type default)
			)
			(fill no)
			(layer "F.CrtYd")
		)
		(fp_poly
			(pts
				(xy 1.651 2.413) (xy 1.651 -2.413) (xy -1.651 -2.413) (xy -1.651 2.413)
			)
			(stroke
				(width 0)
				(type default)
			)
			(fill no)
			(layer "F.Fab")
		)
		(pad "1" smd rect
			(at 0 -1.4732 90)
			(size 2.794 1.397)
			(layers "F.Cu" "F.Mask" "F.Paste")
			(net "GND")
		)
		(pad "2" smd rect
			(at 0 1.4732 90)
			(size 2.794 1.397)
			(layers "F.Cu" "F.Mask" "F.Paste")
			(net "PCE_AVDD")
		)
	)
	(footprint ""
		(layer "F.Cu")
		(at 318.008 -169.418 -90)
		(property "Reference" "R461"
			(at 0 0 270)
			(layer "F.SilkS")
			(hide yes)
			(effects
				(font
					(size 1.27 1.27)
				)
			)
		)
		(property "Value" "0R2J-2-GP"
			(at 0.064008 -3.993896 270)
			(unlocked yes)
			(layer "F.Fab")
			(hide yes)
			(effects
				(font
					(size 1.016 1.016)
					(thickness 0.1524)
				)
			)
		)
		(property "Device Type" "R402H16"
			(at 0.064008 -5.517896 270)
			(unlocked yes)
			(layer "F.Fab")
			(hide yes)
			(effects
				(font
					(size 1.016 1.016)
					(thickness 0.1524)
				)
			)
		)
		(duplicate_pad_numbers_are_jumpers no)
		(fp_line
			(start -0.508 -0.9398)
			(end -0.508 0.9398)
			(stroke
				(width 0.1524)
				(type default)
			)
			(layer "F.SilkS")
		)
		(fp_line
			(start 0.508 -0.9398)
			(end -0.508 -0.9398)
			(stroke
				(width 0.1524)
				(type default)
			)
			(layer "F.SilkS")
		)
		(fp_rect
			(start -0.508 0.9398)
			(end 0.508 -0.9398)
			(stroke
				(width 0)
				(type default)
			)
			(fill no)
			(layer "F.CrtYd")
		)
		(fp_rect
			(start -0.508 0.9398)
			(end 0.508 -0.9398)
			(stroke
				(width 0)
				(type default)
			)
			(fill no)
			(layer "F.Fab")
		)
		(pad "1" smd custom
			(at 0 -0.4445 270)
			(size 0.1397 0.1397)
			(layers "F.Cu" "F.Mask" "F.Paste")
			(net "BMC_I2C_B_SCL")
			(options
				(clearance outline)
				(anchor circle)
			)
			(primitives
				(gr_poly
					(pts
						(arc
							(start -0.1778 -0.2794)
							(mid -0.249642 -0.249642)
							(end -0.2794 -0.1778)
						)
						(arc
							(start -0.2794 0.1778)
							(mid -0.249642 0.249642)
							(end -0.1778 0.2794)
						)
						(arc
							(start 0.1778 0.2794)
							(mid 0.249642 0.249642)
							(end 0.2794 0.1778)
						)
						(arc
							(start 0.2794 -0.1778)
							(mid 0.249642 -0.249642)
							(end 0.1778 -0.2794)
						)
					)
					(width 0)
					(fill yes)
				)
			)
		)
		(pad "2" smd custom
			(at 0 0.4445 270)
			(size 0.1397 0.1397)
			(layers "F.Cu" "F.Mask" "F.Paste")
			(net "BMC0_SMB7_CLK")
			(options
				(clearance outline)
				(anchor circle)
			)
			(primitives
				(gr_poly
					(pts
						(arc
							(start -0.1778 -0.2794)
							(mid -0.249642 -0.249642)
							(end -0.2794 -0.1778)
						)
						(arc
							(start -0.2794 0.1778)
							(mid -0.249642 0.249642)
							(end -0.1778 0.2794)
						)
						(arc
							(start 0.1778 0.2794)
							(mid 0.249642 0.249642)
							(end 0.2794 0.1778)
						)
						(arc
							(start 0.2794 -0.1778)
							(mid 0.249642 -0.249642)
							(end 0.1778 -0.2794)
						)
					)
					(width 0)
					(fill yes)
				)
			)
		)
	)
)
